# BASEBOARD_FAB2 (Tioga Pass) — schematic netlist excerpt (pin names and nets, part order shuffled) for the footprints in the layout excerpt that follows; sources: Cadence DE-HDL packaged netlist, KiCad conversion of Wiwynn_Tioga_Pass_MB.brd

C1A2  SC1U10V2KX-4-GP  10%  pkg SMD-BCG6  page 227 : \1\ = P5V_STBY ; \2\ = GND

U9E1  M25PE16  IC  pkg SM  page 140
  S_N  = SPI_NIC_CS_N
  DQ1  = SPI_NIC_MISO_R
  W_N  = PU_NV_WP_N
  VSS  = GND
  DQ0  = SPI_NIC_MOSI
  C  = SPI_NIC_SCLK
  RESET_N  = PU_NV_HOLD_N
  VCC  = P3V3_STBY

(kicad_pcb
	(version 20260206)
	(generator "pcbnew")
	(generator_version "10.0")
	(general
		(thickness 1.6)
		(legacy_teardrops no)
	)
	(paper "A4")
	(title_block
		(title "Wiwynn_Tioga_Pass_MB.brd")
		(comment 1 "Tioga Pass / footprints 3208-3209 of 4770")
	)
	(layers
		(0 "F.Cu" signal "TOP")
		(4 "In1.Cu" signal "L2GND")
		(6 "In2.Cu" signal "L3")
		(8 "In3.Cu" signal "L4GND")
		(10 "In4.Cu" signal "L5")
		(12 "In5.Cu" signal "L6GND")
		(14 "In6.Cu" signal "L7VCC")
		(16 "In7.Cu" signal "L8VCC")
		(18 "In8.Cu" signal "L9GND")
		(20 "In9.Cu" signal "L10")
		(22 "In10.Cu" signal "L11GND")
		(24 "In11.Cu" signal "L12")
		(26 "In12.Cu" signal "L13GND")
		(2 "B.Cu" signal "BOTTOM")
		(9 "F.Adhes" user "F.Adhesive")
		(11 "B.Adhes" user "B.Adhesive")
		(13 "F.Paste" user "Package Geometry/Pastemask Top")
		(15 "B.Paste" user "Package Geometry/Pastemask Bottom")
		(5 "F.SilkS" user "Ref Des/Silkscreen Top")
		(7 "B.SilkS" user "Ref Des/Silkscreen Bottom")
		(1 "F.Mask" user "Board Geometry/Soldermask Top")
		(3 "B.Mask" user "Board Geometry/Soldermask Bottom")
		(17 "Dwgs.User" user "User.Drawings")
		(19 "Cmts.User" user "User.Comments")
		(21 "Eco1.User" user "User.Eco1")
		(23 "Eco2.User" user "User.Eco2")
		(25 "Edge.Cuts" user "Board Geometry/Outline")
		(27 "Margin" user)
		(31 "F.CrtYd" user "Package Geometry/Place Bound Top")
		(29 "B.CrtYd" user "Package Geometry/Place Bound Bottom")
		(35 "F.Fab" user "Ref Des/Assembly Top")
		(33 "B.Fab" user "Ref Des/Assembly Bottom")
	)
	(footprint ""
		(layer "B.Cu")
		(at 491.078266 -20.00758 -90)
		(property "Reference" "U9E1"
			(at -4.7498 -1.51257 90)
			(unlocked yes)
			(layer "B.SilkS")
			(effects
				(font
					(size 0.7874 0.5842)
					(thickness 0.1524)
				)
				(justify left mirror)
			)
		)
		(property "Value" ""
			(at 0 0 90)
			(layer "B.Fab")
			(effects
				(font
					(size 1.27 1.27)
				)
				(justify mirror)
			)
		)
		(duplicate_pad_numbers_are_jumpers no)
		(fp_line
			(start -4.826 4.6355)
			(end -1.905 4.6355)
			(stroke
				(width 0.1524)
				(type default)
			)
			(layer "B.SilkS")
		)
		(fp_line
			(start -1.905 4.6355)
			(end -1.905 -0.8255)
			(stroke
				(width 0.1524)
				(type default)
			)
			(layer "B.SilkS")
		)
		(fp_line
			(start -4.0132 0.6731)
			(end -4.0132 -0.8255)
			(stroke
				(width 0.1524)
				(type default)
			)
			(layer "B.SilkS")
		)
		(fp_line
			(start -2.7432 0.6731)
			(end -4.0132 0.6731)
			(stroke
				(width 0.1524)
				(type default)
			)
			(layer "B.SilkS")
		)
		(fp_line
			(start -4.826 -0.8255)
			(end -4.826 4.6355)
			(stroke
				(width 0.1524)
				(type default)
			)
			(layer "B.SilkS")
		)
		(fp_line
			(start -2.7432 -0.8255)
			(end -2.7432 0.6731)
			(stroke
				(width 0.1524)
				(type default)
			)
			(layer "B.SilkS")
		)
		(fp_line
			(start -1.905 -0.8255)
			(end -4.826 -0.8255)
			(stroke
				(width 0.1524)
				(type default)
			)
			(layer "B.SilkS")
		)
		(fp_circle
			(center 1.016 -1.27)
			(end 1.016 -1.4605)
			(stroke
				(width 0.381)
				(type default)
			)
			(fill no)
			(layer "B.SilkS")
		)
		(fp_poly
			(pts
				(xy -6.0833 -0.8255) (xy -6.0833 4.6355) (xy -0.6731 4.6355) (xy -0.6731 -0.8255)
			)
			(stroke
				(width 0)
				(type default)
			)
			(fill no)
			(layer "B.CrtYd")
		)
		(fp_line
			(start -4.0132 0.6731)
			(end -4.0132 -0.8255)
			(stroke
				(width 0.1)
				(type default)
			)
			(layer "B.Fab")
		)
		(fp_line
			(start -2.7432 0.6731)
			(end -4.0132 0.6731)
			(stroke
				(width 0.1)
				(type default)
			)
			(layer "B.Fab")
		)
		(fp_line
			(start -2.7432 -0.8255)
			(end -2.7432 0.6731)
			(stroke
				(width 0.1)
				(type default)
			)
			(layer "B.Fab")
		)
		(fp_rect
			(start -0.6731 4.6355)
			(end -6.0833 -0.8255)
			(stroke
				(width 0)
				(type default)
			)
			(fill no)
			(layer "B.Fab")
		)
		(fp_circle
			(center 1.016 -1.27)
			(end 1.016 -1.4605)
			(stroke
				(width 0.381)
				(type default)
			)
			(fill no)
			(layer "B.Fab")
		)
		(pad "1" smd rect
			(at 0 0 90)
			(size 1.9304 0.635)
			(layers "B.Cu" "B.Mask" "B.Paste")
			(net "SPI_NIC_CS_N")
		)
		(pad "2" smd rect
			(at 0 1.27 90)
			(size 1.9304 0.635)
			(layers "B.Cu" "B.Mask" "B.Paste")
			(net "SPI_NIC_MISO_R")
		)
		(pad "3" smd rect
			(at 0 2.54 90)
			(size 1.9304 0.635)
			(layers "B.Cu" "B.Mask" "B.Paste")
			(net "PU_NV_WP_N")
		)
		(pad "4" smd rect
			(at 0 3.81 90)
			(size 1.9304 0.635)
			(layers "B.Cu" "B.Mask" "B.Paste")
			(net "GND")
		)
		(pad "5" smd rect
			(at -6.7564 3.81 90)
			(size 1.9304 0.635)
			(layers "B.Cu" "B.Mask" "B.Paste")
			(net "SPI_NIC_MOSI")
		)
		(pad "6" smd rect
			(at -6.7564 2.54 90)
			(size 1.9304 0.635)
			(layers "B.Cu" "B.Mask" "B.Paste")
			(net "SPI_NIC_SCLK")
		)
		(pad "7" smd rect
			(at -6.7564 1.27 90)
			(size 1.9304 0.635)
			(layers "B.Cu" "B.Mask" "B.Paste")
			(net "PU_NV_HOLD_N")
		)
		(pad "8" smd rect
			(at -6.7564 0 90)
			(size 1.9304 0.635)
			(layers "B.Cu" "B.Mask" "B.Paste")
			(net "P3V3_STBY")
		)
	)
	(footprint ""
		(layer "B.Cu")
		(at 2.62382 -134.38632 90)
		(property "Reference" "C1A2"
			(at 0 0 90)
			(layer "B.SilkS")
			(hide yes)
			(effects
				(font
					(size 1.27 1.27)
				)
				(justify mirror)
			)
		)
		(property "Value" "*"
			(at -1.1811 -2.8194 90)
			(unlocked yes)
			(layer "B.Fab")
			(hide yes)
			(effects
				(font
					(size 1.27 1.016)
					(thickness 0.1524)
				)
				(justify mirror)
			)
		)
		(property "Device Type" "SC1U10V2KX-4-GP_SMD-BCG6-SC1U1A"
			(at -1.1811 -4.3434 90)
			(unlocked yes)
			(layer "B.Fab")
			(hide yes)
			(effects
				(font
					(size 1.27 1.016)
					(thickness 0.1524)
				)
				(justify mirror)
			)
		)
		(duplicate_pad_numbers_are_jumpers no)
		(fp_rect
			(start 0.4318 0.9525)
			(end -0.4318 -0.9525)
			(stroke
				(width 0)
				(type default)
			)
			(fill no)
			(layer "B.CrtYd")
		)
		(fp_rect
			(start 0.4318 0.9525)
			(end -0.4318 -0.9525)
			(stroke
				(width 0)
				(type default)
			)
			(fill no)
			(layer "B.Fab")
		)
		(pad "1" smd custom
			(at 0 -0.4445 270)
			(size 0.1524 0.1524)
			(layers "B.Cu" "B.Mask" "B.Paste")
			(net "P5V_STBY")
			(options
				(clearance outline)
				(anchor circle)
			)
			(primitives
				(gr_poly
					(pts
						(arc
							(start 0.3048 0.2032)
							(mid 0.275042 0.275042)
							(end 0.2032 0.3048)
						)
						(arc
							(start -0.2032 0.3048)
							(mid -0.275042 0.275042)
							(end -0.3048 0.2032)
						)
						(arc
							(start -0.3048 -0.2032)
							(mid -0.275042 -0.275042)
							(end -0.2032 -0.3048)
						)
						(arc
							(start 0.2032 -0.3048)
							(mid 0.275042 -0.275042)
							(end 0.3048 -0.2032)
						)
					)
					(width 0)
					(fill yes)
				)
			)
		)
		(pad "2" smd custom
			(at 0 0.4445 270)
			(size 0.1524 0.1524)
			(layers "B.Cu" "B.Mask" "B.Paste")
			(net "GND")
			(options
				(clearance outline)
				(anchor circle)
			)
			(primitives
				(gr_poly
					(pts
						(arc
							(start 0.3048 0.2032)
							(mid 0.275042 0.275042)
							(end 0.2032 0.3048)
						)
						(arc
							(start -0.2032 0.3048)
							(mid -0.275042 0.275042)
							(end -0.3048 0.2032)
						)
						(arc
							(start -0.3048 -0.2032)
							(mid -0.275042 -0.275042)
							(end -0.2032 -0.3048)
						)
						(arc
							(start 0.2032 -0.3048)
							(mid 0.275042 -0.275042)
							(end 0.3048 -0.2032)
						)
					)
					(width 0)
					(fill yes)
				)
			)
		)
	)
)
